FILE_TYPE = MULTI_PHYS_TABLE;
PART 'PXE1610B'
{========================================================================================================================================================================================}
:PACK_TYPE | MATERIAL | PART_NUMBER     = EnvComp | PART_NUMBER  | JEDEC_TYPE     | DESCRIPTION                                             | CLASS | COMPONENT_TYPE | HEIGHT     | LPID  | SPEED_URL | Status |RPL| AML | Bus_Unit | Days ;
{========================================================================================================================================================================================}
'QFN'      | 'IC'     | 'H79206-001'(!) = ''      | 'H79206-001' | 'QFN48_24_4MH' | 'IC,LIN,QFN,PXE1610B,CONTROLR'                          | 'IC'  | 'LCC'          | '0.035 IN' | '3252' | 'http://speed.intel.com:8081/speed/module/pdm/item/pdm_item_detail_direct.asp?item_cde=H79206-001&item_rev=01&url_param=unused' | '' | '' | '' | '' | '' 
'QFN'      | 'EMPTY'  | 'H79206-001'(!) = ''      | 'H79206-001' | 'QFN48_24_4MH' | 'IC,LIN,QFN,PXE1610B,CONTROLR'                          | 'IO'  | 'LCC'          | '0.035 IN' | '3252' | 'http://speed.intel.com:8081/speed/module/pdm/item/pdm_item_detail_direct.asp?item_cde=H79206-001&item_rev=01&url_param=unused' | '' | '' | '' | '' | '' 
END_PART
END.
